# S9S_MB_2U (Grand Teton) — schematic netlist excerpt (pin names and nets, part order shuffled) for the footprints in the layout excerpt that follows; sources: Cadence DE-HDL packaged netlist, KiCad conversion of 03242023_DA0F0TMBIJ0_F0T_Motherboard_J_brd_V01_OCP.brd

PC1177  Q_CAP  100NF 50V 10% X7R  pkg C0402  page 272 : A = SW_PVCCFA_EHV_FIVRA_CPU0_BOOT3_ ; B = SW_PVCCFA_EHV_FIVRA_CPU0_BOOTR3
R283  Q_RES  10K 1% CHIP  pkg 0402LF  page 119 : A = P3V3_AUX ; B = FM_CPU0_PKGID0
H16  HOLE  EMPTY  pkg TH  page 311 : \1\ = NC

(kicad_pcb
	(version 20260206)
	(generator "pcbnew")
	(generator_version "10.0")
	(general
		(thickness 1.6)
		(legacy_teardrops no)
	)
	(paper "A4")
	(title_block
		(title "03242023_DA0F0TMBIJ0_F0T_Motherboard_J_brd_V01_OCP.brd")
		(comment 1 "Grand Teton / footprints 934-936 of 6105")
	)
	(layers
		(0 "F.Cu" signal "TOP")
		(4 "In1.Cu" signal "GND")
		(6 "In2.Cu" signal "IN1")
		(8 "In3.Cu" signal "GND1")
		(10 "In4.Cu" signal "IN2")
		(12 "In5.Cu" signal "GND2")
		(14 "In6.Cu" signal "IN3")
		(16 "In7.Cu" signal "GND3")
		(18 "In8.Cu" signal "VCC")
		(20 "In9.Cu" signal "VCC1")
		(22 "In10.Cu" signal "GND4")
		(24 "In11.Cu" signal "IN4")
		(26 "In12.Cu" signal "GND5")
		(28 "In13.Cu" signal "IN5")
		(30 "In14.Cu" signal "GND6")
		(32 "In15.Cu" signal "IN6")
		(34 "In16.Cu" signal "GND7")
		(2 "B.Cu" signal "BOTTOM")
		(9 "F.Adhes" user "F.Adhesive")
		(11 "B.Adhes" user "B.Adhesive")
		(13 "F.Paste" user "Package Geometry/Pastemask Top")
		(15 "B.Paste" user "Package Geometry/Pastemask Bottom")
		(5 "F.SilkS" user "Ref Des/Silkscreen Top")
		(7 "B.SilkS" user "Ref Des/Silkscreen Bottom")
		(1 "F.Mask" user "Board Geometry/Soldermask Top")
		(3 "B.Mask" user "Board Geometry/Soldermask Bottom")
		(17 "Dwgs.User" user "User.Drawings")
		(19 "Cmts.User" user "User.Comments")
		(21 "Eco1.User" user "User.Eco1")
		(23 "Eco2.User" user "User.Eco2")
		(25 "Edge.Cuts" user "Board Geometry/Outline")
		(27 "Margin" user)
		(31 "F.CrtYd" user "Package Geometry/Place Bound Top")
		(29 "B.CrtYd" user "Package Geometry/Place Bound Bottom")
		(35 "F.Fab" user "Ref Des/Assembly Top")
		(33 "B.Fab" user "Ref Des/Assembly Bottom")
	)
	(footprint ""
		(layer "F.Cu")
		(at 427.634654 -366.691164 -90)
		(property "Reference" "PC1177"
			(at 0 0 270)
			(layer "F.SilkS")
			(hide yes)
			(effects
				(font
					(size 1.27 1.27)
				)
			)
		)
		(property "Value" ""
			(at 0 0 270)
			(layer "F.Fab")
			(effects
				(font
					(size 1.27 1.27)
				)
			)
		)
		(duplicate_pad_numbers_are_jumpers no)
		(fp_line
			(start -0.7874 0.4064)
			(end -0.7874 -0.4064)
			(stroke
				(width 0.1524)
				(type default)
			)
			(layer "F.SilkS")
		)
		(fp_line
			(start 0.7874 0.4064)
			(end -0.7874 0.4064)
			(stroke
				(width 0.1524)
				(type default)
			)
			(layer "F.SilkS")
		)
		(fp_line
			(start -0.7874 -0.4064)
			(end 0.7874 -0.4064)
			(stroke
				(width 0.1524)
				(type default)
			)
			(layer "F.SilkS")
		)
		(fp_line
			(start 0.7874 -0.4064)
			(end 0.7874 0.4064)
			(stroke
				(width 0.1524)
				(type default)
			)
			(layer "F.SilkS")
		)
		(fp_line
			(start -0.67945 0.3048)
			(end -0.67945 -0.305054)
			(stroke
				(width 0.1)
				(type default)
			)
			(layer "F.Fab")
		)
		(fp_line
			(start -0.12065 0.3048)
			(end -0.67945 0.3048)
			(stroke
				(width 0.1)
				(type default)
			)
			(layer "F.Fab")
		)
		(fp_line
			(start 0.120396 0.3048)
			(end 0.120396 0.2794)
			(stroke
				(width 0.1)
				(type default)
			)
			(layer "F.Fab")
		)
		(fp_line
			(start 0.67945 0.3048)
			(end 0.120396 0.3048)
			(stroke
				(width 0.1)
				(type default)
			)
			(layer "F.Fab")
		)
		(fp_line
			(start -0.12065 0.2794)
			(end -0.12065 0.3048)
			(stroke
				(width 0.1)
				(type default)
			)
			(layer "F.Fab")
		)
		(fp_line
			(start 0.120396 0.2794)
			(end -0.12065 0.2794)
			(stroke
				(width 0.1)
				(type default)
			)
			(layer "F.Fab")
		)
		(fp_line
			(start -0.12065 -0.2794)
			(end 0.12065 -0.2794)
			(stroke
				(width 0.1)
				(type default)
			)
			(layer "F.Fab")
		)
		(fp_line
			(start 0.12065 -0.2794)
			(end 0.12065 -0.3048)
			(stroke
				(width 0.1)
				(type default)
			)
			(layer "F.Fab")
		)
		(fp_line
			(start 0.12065 -0.3048)
			(end 0.67945 -0.3048)
			(stroke
				(width 0.1)
				(type default)
			)
			(layer "F.Fab")
		)
		(fp_line
			(start 0.67945 -0.3048)
			(end 0.67945 0.3048)
			(stroke
				(width 0.1)
				(type default)
			)
			(layer "F.Fab")
		)
		(fp_line
			(start -0.67945 -0.305054)
			(end -0.12065 -0.305054)
			(stroke
				(width 0.1)
				(type default)
			)
			(layer "F.Fab")
		)
		(fp_line
			(start -0.12065 -0.305054)
			(end -0.12065 -0.2794)
			(stroke
				(width 0.1)
				(type default)
			)
			(layer "F.Fab")
		)
		(pad "1" smd circle
			(at -0.40005 0 270)
			(size 0 0)
			(layers "F.Cu" "F.Mask" "F.Paste")
			(net "SW_PVCCFA_EHV_FIVRA_CPU0_BOOT3_")
		)
		(pad "2" smd circle
			(at 0.40005 0 270)
			(size 0 0)
			(layers "F.Cu" "F.Mask" "F.Paste")
			(net "SW_PVCCFA_EHV_FIVRA_CPU0_BOOTR3")
		)
	)
	(footprint ""
		(layer "F.Cu")
		(at 183.69788 -130.266948 -90)
		(property "Reference" "R283"
			(at 0 0 270)
			(layer "F.SilkS")
			(hide yes)
			(effects
				(font
					(size 1.27 1.27)
				)
			)
		)
		(property "Value" ""
			(at 0 0 270)
			(layer "F.Fab")
			(effects
				(font
					(size 1.27 1.27)
				)
			)
		)
		(duplicate_pad_numbers_are_jumpers no)
		(fp_line
			(start -0.7874 0.4064)
			(end -0.7874 -0.4064)
			(stroke
				(width 0.1524)
				(type default)
			)
			(layer "F.SilkS")
		)
		(fp_line
			(start 0.7874 0.4064)
			(end -0.7874 0.4064)
			(stroke
				(width 0.1524)
				(type default)
			)
			(layer "F.SilkS")
		)
		(fp_line
			(start -0.7874 -0.4064)
			(end 0.7874 -0.4064)
			(stroke
				(width 0.1524)
				(type default)
			)
			(layer "F.SilkS")
		)
		(fp_line
			(start 0.7874 -0.4064)
			(end 0.7874 0.4064)
			(stroke
				(width 0.1524)
				(type default)
			)
			(layer "F.SilkS")
		)
		(fp_line
			(start -0.67945 0.3048)
			(end -0.67945 -0.305054)
			(stroke
				(width 0.1)
				(type default)
			)
			(layer "F.Fab")
		)
		(fp_line
			(start -0.12065 0.3048)
			(end -0.67945 0.3048)
			(stroke
				(width 0.1)
				(type default)
			)
			(layer "F.Fab")
		)
		(fp_line
			(start 0.120396 0.3048)
			(end 0.120396 0.2794)
			(stroke
				(width 0.1)
				(type default)
			)
			(layer "F.Fab")
		)
		(fp_line
			(start 0.67945 0.3048)
			(end 0.120396 0.3048)
			(stroke
				(width 0.1)
				(type default)
			)
			(layer "F.Fab")
		)
		(fp_line
			(start -0.12065 0.2794)
			(end -0.12065 0.3048)
			(stroke
				(width 0.1)
				(type default)
			)
			(layer "F.Fab")
		)
		(fp_line
			(start 0.120396 0.2794)
			(end -0.12065 0.2794)
			(stroke
				(width 0.1)
				(type default)
			)
			(layer "F.Fab")
		)
		(fp_line
			(start -0.12065 -0.2794)
			(end 0.12065 -0.2794)
			(stroke
				(width 0.1)
				(type default)
			)
			(layer "F.Fab")
		)
		(fp_line
			(start 0.12065 -0.2794)
			(end 0.12065 -0.3048)
			(stroke
				(width 0.1)
				(type default)
			)
			(layer "F.Fab")
		)
		(fp_line
			(start 0.12065 -0.3048)
			(end 0.67945 -0.3048)
			(stroke
				(width 0.1)
				(type default)
			)
			(layer "F.Fab")
		)
		(fp_line
			(start 0.67945 -0.3048)
			(end 0.67945 0.3048)
			(stroke
				(width 0.1)
				(type default)
			)
			(layer "F.Fab")
		)
		(fp_line
			(start -0.67945 -0.305054)
			(end -0.12065 -0.305054)
			(stroke
				(width 0.1)
				(type default)
			)
			(layer "F.Fab")
		)
		(fp_line
			(start -0.12065 -0.305054)
			(end -0.12065 -0.2794)
			(stroke
				(width 0.1)
				(type default)
			)
			(layer "F.Fab")
		)
		(pad "1" smd circle
			(at -0.40005 0 270)
			(size 0 0)
			(layers "F.Cu" "F.Mask" "F.Paste")
			(net "P3V3_AUX")
		)
		(pad "2" smd circle
			(at 0.40005 0 270)
			(size 0 0)
			(layers "F.Cu" "F.Mask" "F.Paste")
			(net "FM_CPU0_PKGID0")
		)
	)
	(footprint ""
		(layer "F.Cu")
		(at 133.420104 -297.514772)
		(property "Reference" "H16"
			(at 0.201676 -6.217666 0)
			(unlocked yes)
			(layer "F.SilkS")
			(effects
				(font
					(size 0.7874 0.5842)
					(thickness 0.1524)
				)
				(justify left)
			)
		)
		(property "Value" ""
			(at 0 0 0)
			(layer "F.Fab")
			(effects
				(font
					(size 1.27 1.27)
				)
			)
		)
		(duplicate_pad_numbers_are_jumpers no)
		(fp_circle
			(center 0 0)
			(end 2.5273 0)
			(stroke
				(width 0.1524)
				(type default)
			)
			(fill no)
			(layer "F.SilkS")
		)
		(fp_circle
			(center 0 0)
			(end 2.5273 0)
			(stroke
				(width 0.1524)
				(type default)
			)
			(fill no)
			(layer "B.SilkS")
		)
		(fp_circle
			(center 0 0)
			(end 2.5273 0)
			(stroke
				(width 0.1)
				(type default)
			)
			(fill no)
			(layer "B.Fab")
		)
		(fp_circle
			(center 0 0)
			(end 2.5273 0)
			(stroke
				(width 0.1)
				(type default)
			)
			(fill no)
			(layer "F.Fab")
		)
		(pad "" np_thru_hole circle
			(at 0 0)
			(size 3.429 3.429)
			(drill 3.429)
			(layers "*.Cu" "*.Mask")
			(clearance 0.381)
			(thermal_gap 0.381)
		)
	)
)
